(kicad_pcb
	(version 20241229)
	(generator "pcbnew")
	(generator_version "9.0")
	(general
		(thickness 1.6)
		(legacy_teardrops no)
	)
	(paper "A4")
	(title_block
		(title "LPDDR4 testbed")
		(date "2024-03-26")
		(rev "1.2.2")
		(comment 9 "footprint 16 of 66 (U1), pads 89-176 of 200")
	)
	(layers
		(0 "F.Cu" signal)
		(4 "In1.Cu" power)
		(6 "In2.Cu" power)
		(8 "In3.Cu" signal)
		(10 "In4.Cu" signal)
		(2 "B.Cu" signal)
		(9 "F.Adhes" user "F.Adhesive")
		(11 "B.Adhes" user "B.Adhesive")
		(13 "F.Paste" user)
		(15 "B.Paste" user)
		(5 "F.SilkS" user "F.Silkscreen")
		(7 "B.SilkS" user "B.Silkscreen")
		(1 "F.Mask" user)
		(3 "B.Mask" user)
		(17 "Dwgs.User" user "User.Drawings")
		(19 "Cmts.User" user "User.Comments")
		(21 "Eco1.User" user "User.Eco1")
		(23 "Eco2.User" user "User.Eco2")
		(25 "Edge.Cuts" user)
		(27 "Margin" user)
		(31 "F.CrtYd" user "F.Courtyard")
		(29 "B.CrtYd" user "B.Courtyard")
		(35 "F.Fab" user)
		(33 "B.Fab" user)
	)
	(footprint "antmicro-footprints:BGA-264-200_10x14.5mm_Layout12x22_P0.8x0.65mm"
		(locked yes)
		(layer "F.Cu")
		(at 149.375 86.125 180)
		(descr "http://www.issi.com/WW/pdf/43-46LQ32256A-AL.pdf")
		(property "Reference" "U1"
			(at 5.2 7.575 180)
			(layer "F.SilkS")
			(effects
				(font
					(size 0.7 0.7)
					(thickness 0.15)
				)
				(justify left bottom)
			)
		)
		(property "Value" "MT53E1G32D2NP-046"
			(at -5.5 9 180)
			(layer "F.Fab")
			(effects
				(font
					(size 0.7 0.7)
					(thickness 0.15)
				)
				(justify left bottom)
			)
		)
		(property "Description" "DRAM, Mobile LPDDR4, 32 Gbit, 1G x 32bit, 2.133 GHz, WFBGA, 200 Pins"
			(at 0 0 180)
			(layer "F.Fab")
			(hide yes)
			(effects
				(font
					(size 1.27 1.27)
					(thickness 0.15)
				)
			)
		)
		(property "Author" "Antmicro"
			(at 298.75 172.25 0)
			(layer "F.Fab")
			(hide yes)
			(effects
				(font
					(size 1 1)
					(thickness 0.15)
				)
			)
		)
		(property "License" "Apache-2.0"
			(at 298.75 172.25 0)
			(layer "F.Fab")
			(hide yes)
			(effects
				(font
					(size 1 1)
					(thickness 0.15)
				)
			)
		)
		(property "MPN" "MT53E1G32D2NP-046 WT:A"
			(at 298.75 172.25 0)
			(layer "F.Fab")
			(hide yes)
			(effects
				(font
					(size 1 1)
					(thickness 0.15)
				)
			)
		)
		(property "Manufacturer" "Micron Technology"
			(at 298.75 172.25 0)
			(layer "F.Fab")
			(hide yes)
			(effects
				(font
					(size 1 1)
					(thickness 0.15)
				)
			)
		)
		(sheetname "LPDDR4")
		(sheetfile "lpddr4.kicad_sch")
		(attr smd)
		(pad "G11" smd circle
			(at 3.604 -2.934 180)
			(size 0.27 0.27)
			(layers "F.Cu" "F.Mask" "F.Paste")
			(net 179 "unconnected-(U1B-NC-PadG11)")
			(pinfunction "NC")
			(pintype "no_connect")
		)
		(pad "G12" smd circle
			(at 4.405 -2.934 180)
			(size 0.27 0.27)
			(layers "F.Cu" "F.Mask" "F.Paste")
			(net 36 "GND")
			(pinfunction "VSS")
			(pintype "passive")
		)
		(pad "H1" smd circle
			(at -4.396 -2.283 180)
			(size 0.27 0.27)
			(layers "F.Cu" "F.Mask" "F.Paste")
			(net 188 "VDD2")
			(pinfunction "VDD2")
			(pintype "passive")
		)
		(pad "H2" smd circle
			(at -3.596 -2.283 180)
			(size 0.27 0.27)
			(layers "F.Cu" "F.Mask" "F.Paste")
			(net 192 "CA0_A")
			(pinfunction "CA0_A")
			(pintype "input")
		)
		(pad "H3" smd circle
			(at -2.795 -2.283 180)
			(size 0.27 0.27)
			(layers "F.Cu" "F.Mask" "F.Paste")
			(net 180 "unconnected-(U1A-NC-PadH3)")
			(pinfunction "NC")
			(pintype "no_connect")
		)
		(pad "H4" smd circle
			(at -1.996 -2.283 180)
			(size 0.27 0.27)
			(layers "F.Cu" "F.Mask" "F.Paste")
			(net 200 "CS0_A")
			(pinfunction "CS0_A")
			(pintype "input")
		)
		(pad "H5" smd circle
			(at -1.196 -2.283 180)
			(size 0.27 0.27)
			(layers "F.Cu" "F.Mask" "F.Paste")
			(net 188 "VDD2")
			(pinfunction "VDD2")
			(pintype "passive")
		)
		(pad "H8" smd circle
			(at 1.205 -2.283 180)
			(size 0.27 0.27)
			(layers "F.Cu" "F.Mask" "F.Paste")
			(net 188 "VDD2")
			(pinfunction "VDD2")
			(pintype "passive")
		)
		(pad "H9" smd circle
			(at 2.004 -2.283 180)
			(size 0.27 0.27)
			(layers "F.Cu" "F.Mask" "F.Paste")
			(net 218 "CA2_A")
			(pinfunction "CA2_A")
			(pintype "input")
		)
		(pad "H10" smd circle
			(at 2.805 -2.283 180)
			(size 0.27 0.27)
			(layers "F.Cu" "F.Mask" "F.Paste")
			(net 219 "CA3_A")
			(pinfunction "CA3_A")
			(pintype "input")
		)
		(pad "H11" smd circle
			(at 3.604 -2.283 180)
			(size 0.27 0.27)
			(layers "F.Cu" "F.Mask" "F.Paste")
			(net 220 "CA4_A")
			(pinfunction "CA4_A")
			(pintype "input")
		)
		(pad "H12" smd circle
			(at 4.405 -2.283 180)
			(size 0.27 0.27)
			(layers "F.Cu" "F.Mask" "F.Paste")
			(net 188 "VDD2")
			(pinfunction "VDD2")
			(pintype "passive")
		)
		(pad "J1" smd circle
			(at -4.396 -1.633 180)
			(size 0.27 0.27)
			(layers "F.Cu" "F.Mask" "F.Paste")
			(net 36 "GND")
			(pinfunction "VSS")
			(pintype "passive")
		)
		(pad "J2" smd circle
			(at -3.596 -1.633 180)
			(size 0.27 0.27)
			(layers "F.Cu" "F.Mask" "F.Paste")
			(net 194 "CA1_A")
			(pinfunction "CA1_A")
			(pintype "input")
		)
		(pad "J3" smd circle
			(at -2.795 -1.633 180)
			(size 0.27 0.27)
			(layers "F.Cu" "F.Mask" "F.Paste")
			(net 36 "GND")
			(pinfunction "VSS")
			(pintype "passive")
		)
		(pad "J4" smd circle
			(at -1.996 -1.633 180)
			(size 0.27 0.27)
			(layers "F.Cu" "F.Mask" "F.Paste")
			(net 199 "CKE0_A")
			(pinfunction "CKE0_A")
			(pintype "input")
		)
		(pad "J5" smd circle
			(at -1.196 -1.633 180)
			(size 0.27 0.27)
			(layers "F.Cu" "F.Mask" "F.Paste")
			(net 181 "unconnected-(U1A-NC-PadJ5)")
			(pinfunction "NC")
			(pintype "no_connect")
		)
		(pad "J8" smd circle
			(at 1.205 -1.633 180)
			(size 0.27 0.27)
			(layers "F.Cu" "F.Mask" "F.Paste")
			(net 216 "CK_T_A")
			(pinfunction "CK_T_A")
			(pintype "input")
		)
		(pad "J9" smd circle
			(at 2.004 -1.633 180)
			(size 0.27 0.27)
			(layers "F.Cu" "F.Mask" "F.Paste")
			(net 214 "CK_C_A")
			(pinfunction "CK_C_A")
			(pintype "input")
		)
		(pad "J10" smd circle
			(at 2.805 -1.633 180)
			(size 0.27 0.27)
			(layers "F.Cu" "F.Mask" "F.Paste")
			(net 36 "GND")
			(pinfunction "VSS")
			(pintype "passive")
		)
		(pad "J11" smd circle
			(at 3.604 -1.633 180)
			(size 0.27 0.27)
			(layers "F.Cu" "F.Mask" "F.Paste")
			(net 221 "CA5_A")
			(pinfunction "CA5_A")
			(pintype "input")
		)
		(pad "J12" smd circle
			(at 4.405 -1.633 180)
			(size 0.27 0.27)
			(layers "F.Cu" "F.Mask" "F.Paste")
			(net 36 "GND")
			(pinfunction "VSS")
			(pintype "passive")
		)
		(pad "K1" smd circle
			(at -4.396 -0.983 180)
			(size 0.27 0.27)
			(layers "F.Cu" "F.Mask" "F.Paste")
			(net 188 "VDD2")
			(pinfunction "VDD2")
			(pintype "passive")
		)
		(pad "K2" smd circle
			(at -3.596 -0.983 180)
			(size 0.27 0.27)
			(layers "F.Cu" "F.Mask" "F.Paste")
			(net 36 "GND")
			(pinfunction "VSS")
			(pintype "passive")
		)
		(pad "K3" smd circle
			(at -2.795 -0.983 180)
			(size 0.27 0.27)
			(layers "F.Cu" "F.Mask" "F.Paste")
			(net 188 "VDD2")
			(pinfunction "VDD2")
			(pintype "passive")
		)
		(pad "K4" smd circle
			(at -1.996 -0.983 180)
			(size 0.27 0.27)
			(layers "F.Cu" "F.Mask" "F.Paste")
			(net 36 "GND")
			(pinfunction "VSS")
			(pintype "passive")
		)
		(pad "K5" smd circle
			(at -1.196 -0.983 180)
			(size 0.27 0.27)
			(layers "F.Cu" "F.Mask" "F.Paste")
			(net 182 "unconnected-(U1A-NC-PadK5)")
			(pinfunction "NC")
			(pintype "no_connect")
		)
		(pad "K8" smd circle
			(at 1.205 -0.983 180)
			(size 0.27 0.27)
			(layers "F.Cu" "F.Mask" "F.Paste")
			(net 183 "unconnected-(U1A-NC-PadK8)")
			(pinfunction "NC")
			(pintype "no_connect")
		)
		(pad "K9" smd circle
			(at 2.004 -0.983 180)
			(size 0.27 0.27)
			(layers "F.Cu" "F.Mask" "F.Paste")
			(net 36 "GND")
			(pinfunction "VSS")
			(pintype "passive")
		)
		(pad "K10" smd circle
			(at 2.805 -0.983 180)
			(size 0.27 0.27)
			(layers "F.Cu" "F.Mask" "F.Paste")
			(net 188 "VDD2")
			(pinfunction "VDD2")
			(pintype "passive")
		)
		(pad "K11" smd circle
			(at 3.604 -0.983 180)
			(size 0.27 0.27)
			(layers "F.Cu" "F.Mask" "F.Paste")
			(net 36 "GND")
			(pinfunction "VSS")
			(pintype "passive")
		)
		(pad "K12" smd circle
			(at 4.405 -0.983 180)
			(size 0.27 0.27)
			(layers "F.Cu" "F.Mask" "F.Paste")
			(net 188 "VDD2")
			(pinfunction "VDD2")
			(pintype "passive")
		)
		(pad "N1" smd circle
			(at -4.396 0.966 180)
			(size 0.27 0.27)
			(layers "F.Cu" "F.Mask" "F.Paste")
			(net 188 "VDD2")
			(pinfunction "VDD2")
			(pintype "passive")
		)
		(pad "N2" smd circle
			(at -3.596 0.966 180)
			(size 0.27 0.27)
			(layers "F.Cu" "F.Mask" "F.Paste")
			(net 36 "GND")
			(pinfunction "VSS")
			(pintype "passive")
		)
		(pad "N3" smd circle
			(at -2.795 0.966 180)
			(size 0.27 0.27)
			(layers "F.Cu" "F.Mask" "F.Paste")
			(net 188 "VDD2")
			(pinfunction "VDD2")
			(pintype "passive")
		)
		(pad "N4" smd circle
			(at -1.996 0.966 180)
			(size 0.27 0.27)
			(layers "F.Cu" "F.Mask" "F.Paste")
			(net 36 "GND")
			(pinfunction "VSS")
			(pintype "passive")
		)
		(pad "N5" smd circle
			(at -1.196 0.966 180)
			(size 0.27 0.27)
			(layers "F.Cu" "F.Mask" "F.Paste")
			(net 184 "unconnected-(U1B-NC-PadN5)")
			(pinfunction "NC")
			(pintype "no_connect")
		)
		(pad "N8" smd circle
			(at 1.205 0.966 180)
			(size 0.27 0.27)
			(layers "F.Cu" "F.Mask" "F.Paste")
			(net 185 "unconnected-(U1B-NC-PadN8)")
			(pinfunction "NC")
			(pintype "no_connect")
		)
		(pad "N9" smd circle
			(at 2.004 0.966 180)
			(size 0.27 0.27)
			(layers "F.Cu" "F.Mask" "F.Paste")
			(net 36 "GND")
			(pinfunction "VSS")
			(pintype "passive")
		)
		(pad "N10" smd circle
			(at 2.805 0.966 180)
			(size 0.27 0.27)
			(layers "F.Cu" "F.Mask" "F.Paste")
			(net 188 "VDD2")
			(pinfunction "VDD2")
			(pintype "passive")
		)
		(pad "N11" smd circle
			(at 3.604 0.966 180)
			(size 0.27 0.27)
			(layers "F.Cu" "F.Mask" "F.Paste")
			(net 36 "GND")
			(pinfunction "VSS")
			(pintype "passive")
		)
		(pad "N12" smd circle
			(at 4.405 0.966 180)
			(size 0.27 0.27)
			(layers "F.Cu" "F.Mask" "F.Paste")
			(net 188 "VDD2")
			(pinfunction "VDD2")
			(pintype "passive")
		)
		(pad "P1" smd circle
			(at -4.396 1.616 180)
			(size 0.27 0.27)
			(layers "F.Cu" "F.Mask" "F.Paste")
			(net 36 "GND")
			(pinfunction "VSS")
			(pintype "passive")
		)
		(pad "P2" smd circle
			(at -3.596 1.616 180)
			(size 0.27 0.27)
			(layers "F.Cu" "F.Mask" "F.Paste")
			(net 186 "unconnected-(U1B-CA1_B-PadP2)")
			(pinfunction "CA1_B")
			(pintype "input+no_connect")
		)
		(pad "P3" smd circle
			(at -2.795 1.616 180)
			(size 0.27 0.27)
			(layers "F.Cu" "F.Mask" "F.Paste")
			(net 36 "GND")
			(pinfunction "VSS")
			(pintype "passive")
		)
		(pad "P4" smd circle
			(at -1.996 1.616 180)
			(size 0.27 0.27)
			(layers "F.Cu" "F.Mask" "F.Paste")
			(net 223 "unconnected-(U1B-CKE0_B-PadP4)")
			(pinfunction "CKE0_B")
			(pintype "input+no_connect")
		)
		(pad "P5" smd circle
			(at -1.196 1.616 180)
			(size 0.27 0.27)
			(layers "F.Cu" "F.Mask" "F.Paste")
			(net 224 "unconnected-(U1B-NC-PadP5)")
			(pinfunction "NC")
			(pintype "no_connect")
		)
		(pad "P8" smd circle
			(at 1.205 1.616 180)
			(size 0.27 0.27)
			(layers "F.Cu" "F.Mask" "F.Paste")
			(net 225 "unconnected-(U1B-CK_T_B-PadP8)")
			(pinfunction "CK_T_B")
			(pintype "input+no_connect")
		)
		(pad "P9" smd circle
			(at 2.004 1.616 180)
			(size 0.27 0.27)
			(layers "F.Cu" "F.Mask" "F.Paste")
			(net 226 "unconnected-(U1B-CK_C_B-PadP9)")
			(pinfunction "CK_C_B")
			(pintype "input+no_connect")
		)
		(pad "P10" smd circle
			(at 2.805 1.616 180)
			(size 0.27 0.27)
			(layers "F.Cu" "F.Mask" "F.Paste")
			(net 36 "GND")
			(pinfunction "VSS")
			(pintype "passive")
		)
		(pad "P11" smd circle
			(at 3.604 1.616 180)
			(size 0.27 0.27)
			(layers "F.Cu" "F.Mask" "F.Paste")
			(net 227 "unconnected-(U1B-CA5_B-PadP11)")
			(pinfunction "CA5_B")
			(pintype "input+no_connect")
		)
		(pad "P12" smd circle
			(at 4.405 1.616 180)
			(size 0.27 0.27)
			(layers "F.Cu" "F.Mask" "F.Paste")
			(net 36 "GND")
			(pinfunction "VSS")
			(pintype "passive")
		)
		(pad "R1" smd circle
			(at -4.396 2.266 180)
			(size 0.27 0.27)
			(layers "F.Cu" "F.Mask" "F.Paste")
			(net 188 "VDD2")
			(pinfunction "VDD2")
			(pintype "passive")
		)
		(pad "R2" smd circle
			(at -3.596 2.266 180)
			(size 0.27 0.27)
			(layers "F.Cu" "F.Mask" "F.Paste")
			(net 228 "unconnected-(U1B-CA0_B-PadR2)")
			(pinfunction "CA0_B")
			(pintype "input+no_connect")
		)
		(pad "R3" smd circle
			(at -2.795 2.266 180)
			(size 0.27 0.27)
			(layers "F.Cu" "F.Mask" "F.Paste")
			(net 231 "unconnected-(U1B-NC-PadR3)")
			(pinfunction "NC")
			(pintype "no_connect")
		)
		(pad "R4" smd circle
			(at -1.996 2.266 180)
			(size 0.27 0.27)
			(layers "F.Cu" "F.Mask" "F.Paste")
			(net 222 "CS0_B")
			(pinfunction "CS0_B")
			(pintype "input")
		)
		(pad "R5" smd circle
			(at -1.196 2.266 180)
			(size 0.27 0.27)
			(layers "F.Cu" "F.Mask" "F.Paste")
			(net 188 "VDD2")
			(pinfunction "VDD2")
			(pintype "passive")
		)
		(pad "R8" smd circle
			(at 1.205 2.266 180)
			(size 0.27 0.27)
			(layers "F.Cu" "F.Mask" "F.Paste")
			(net 188 "VDD2")
			(pinfunction "VDD2")
			(pintype "passive")
		)
		(pad "R9" smd circle
			(at 2.004 2.266 180)
			(size 0.27 0.27)
			(layers "F.Cu" "F.Mask" "F.Paste")
			(net 232 "unconnected-(U1B-CA2_B-PadR9)")
			(pinfunction "CA2_B")
			(pintype "input+no_connect")
		)
		(pad "R10" smd circle
			(at 2.805 2.266 180)
			(size 0.27 0.27)
			(layers "F.Cu" "F.Mask" "F.Paste")
			(net 233 "unconnected-(U1B-CA3_B-PadR10)")
			(pinfunction "CA3_B")
			(pintype "input+no_connect")
		)
		(pad "R11" smd circle
			(at 3.604 2.266 180)
			(size 0.27 0.27)
			(layers "F.Cu" "F.Mask" "F.Paste")
			(net 234 "unconnected-(U1B-CA4_B-PadR11)")
			(pinfunction "CA4_B")
			(pintype "input+no_connect")
		)
		(pad "R12" smd circle
			(at 4.405 2.266 180)
			(size 0.27 0.27)
			(layers "F.Cu" "F.Mask" "F.Paste")
			(net 188 "VDD2")
			(pinfunction "VDD2")
			(pintype "passive")
		)
		(pad "T1" smd circle
			(at -4.396 2.917 180)
			(size 0.27 0.27)
			(layers "F.Cu" "F.Mask" "F.Paste")
			(net 36 "GND")
			(pinfunction "VSS")
			(pintype "passive")
		)
		(pad "T2" smd circle
			(at -3.596 2.917 180)
			(size 0.27 0.27)
			(layers "F.Cu" "F.Mask" "F.Paste")
			(net 159 "Net-(U1B-ODT_CA_B)")
			(pinfunction "ODT_CA_B")
			(pintype "input")
		)
		(pad "T3" smd circle
			(at -2.795 2.917 180)
			(size 0.27 0.27)
			(layers "F.Cu" "F.Mask" "F.Paste")
			(net 36 "GND")
			(pinfunction "VSS")
			(pintype "passive")
		)
		(pad "T4" smd circle
			(at -1.996 2.917 180)
			(size 0.27 0.27)
			(layers "F.Cu" "F.Mask" "F.Paste")
			(net 187 "VDD1")
			(pinfunction "VDD1")
			(pintype "power_in")
		)
		(pad "T5" smd circle
			(at -1.196 2.917 180)
			(size 0.27 0.27)
			(layers "F.Cu" "F.Mask" "F.Paste")
			(net 36 "GND")
			(pinfunction "VSS")
			(pintype "passive")
		)
		(pad "T8" smd circle
			(at 1.205 2.917 180)
			(size 0.27 0.27)
			(layers "F.Cu" "F.Mask" "F.Paste")
			(net 36 "GND")
			(pinfunction "VSS")
			(pintype "passive")
		)
		(pad "T9" smd circle
			(at 2.004 2.917 180)
			(size 0.27 0.27)
			(layers "F.Cu" "F.Mask" "F.Paste")
			(net 187 "VDD1")
			(pinfunction "VDD1")
			(pintype "passive")
		)
		(pad "T10" smd circle
			(at 2.805 2.917 180)
			(size 0.27 0.27)
			(layers "F.Cu" "F.Mask" "F.Paste")
			(net 36 "GND")
			(pinfunction "VSS")
			(pintype "passive")
		)
		(pad "T11" smd circle
			(at 3.604 2.917 180)
			(size 0.27 0.27)
			(layers "F.Cu" "F.Mask" "F.Paste")
			(net 160 "Net-(U1A-RESET_N)")
			(pinfunction "RESET_N")
			(pintype "input")
		)
		(pad "T12" smd circle
			(at 4.405 2.917 180)
			(size 0.27 0.27)
			(layers "F.Cu" "F.Mask" "F.Paste")
			(net 36 "GND")
			(pinfunction "VSS")
			(pintype "passive")
		)
		(pad "U1" smd circle
			(at -4.396 3.567 180)
			(size 0.27 0.27)
			(layers "F.Cu" "F.Mask" "F.Paste")
			(net 187 "VDD1")
			(pinfunction "VDD1")
			(pintype "passive")
		)
		(pad "U2" smd circle
			(at -3.596 3.567 180)
			(size 0.27 0.27)
			(layers "F.Cu" "F.Mask" "F.Paste")
			(net 235 "unconnected-(U1B-DQ3_B-PadU2)")
			(pinfunction "DQ3_B")
			(pintype "bidirectional+no_connect")
		)
		(pad "U3" smd circle
			(at -2.795 3.567 180)
			(size 0.27 0.27)
			(layers "F.Cu" "F.Mask" "F.Paste")
			(net 189 "VDDQ")
			(pinfunction "VDDQ")
			(pintype "passive")
		)
		(pad "U4" smd circle
			(at -1.996 3.567 180)
			(size 0.27 0.27)
			(layers "F.Cu" "F.Mask" "F.Paste")
			(net 236 "unconnected-(U1B-DQ4_B-PadU4)")
			(pinfunction "DQ4_B")
			(pintype "bidirectional+no_connect")
		)
		(pad "U5" smd circle
			(at -1.196 3.567 180)
			(size 0.27 0.27)
			(layers "F.Cu" "F.Mask" "F.Paste")
			(net 188 "VDD2")
			(pinfunction "VDD2")
			(pintype "passive")
		)
		(pad "U8" smd circle
			(at 1.205 3.567 180)
			(size 0.27 0.27)
			(layers "F.Cu" "F.Mask" "F.Paste")
			(net 188 "VDD2")
			(pinfunction "VDD2")
			(pintype "passive")
		)
		(pad "U9" smd circle
			(at 2.004 3.567 180)
			(size 0.27 0.27)
			(layers "F.Cu" "F.Mask" "F.Paste")
			(net 237 "unconnected-(U1B-DQ12_B-PadU9)")
			(pinfunction "DQ12_B")
			(pintype "bidirectional+no_connect")
		)
		(pad "U10" smd circle
			(at 2.805 3.567 180)
			(size 0.27 0.27)
			(layers "F.Cu" "F.Mask" "F.Paste")
			(net 189 "VDDQ")
			(pinfunction "VDDQ")
			(pintype "passive")
		)
		(pad "U11" smd circle
			(at 3.604 3.567 180)
			(size 0.27 0.27)
			(layers "F.Cu" "F.Mask" "F.Paste")
			(net 238 "unconnected-(U1B-DQ11_B-PadU11)")
			(pinfunction "DQ11_B")
			(pintype "bidirectional+no_connect")
		)
		(pad "U12" smd circle
			(at 4.405 3.567 180)
			(size 0.27 0.27)
			(layers "F.Cu" "F.Mask" "F.Paste")
			(net 187 "VDD1")
			(pinfunction "VDD1")
			(pintype "passive")
		)
		(pad "V1" smd circle
			(at -4.396 4.217 180)
			(size 0.27 0.27)
			(layers "F.Cu" "F.Mask" "F.Paste")
			(net 36 "GND")
			(pinfunction "VSS")
			(pintype "passive")
		)
		(pad "V2" smd circle
			(at -3.596 4.217 180)
			(size 0.27 0.27)
			(layers "F.Cu" "F.Mask" "F.Paste")
			(net 239 "unconnected-(U1B-DQ2_B-PadV2)")
			(pinfunction "DQ2_B")
			(pintype "bidirectional+no_connect")
		)
		(pad "V3" smd circle
			(at -2.795 4.217 180)
			(size 0.27 0.27)
			(layers "F.Cu" "F.Mask" "F.Paste")
			(net 240 "unconnected-(U1B-DQS0_C_B-PadV3)")
			(pinfunction "DQS0_C_B")
			(pintype "bidirectional+no_connect")
		)
		(pad "V4" smd circle
			(at -1.996 4.217 180)
			(size 0.27 0.27)
			(layers "F.Cu" "F.Mask" "F.Paste")
			(net 242 "unconnected-(U1B-DQ5_B-PadV4)")
			(pinfunction "DQ5_B")
			(pintype "bidirectional+no_connect")
		)
		(pad "V5" smd circle
			(at -1.196 4.217 180)
			(size 0.27 0.27)
			(layers "F.Cu" "F.Mask" "F.Paste")
			(net 36 "GND")
			(pinfunction "VSS")
			(pintype "passive")
		)
		(pad "V8" smd circle
			(at 1.205 4.217 180)
			(size 0.27 0.27)
			(layers "F.Cu" "F.Mask" "F.Paste")
			(net 36 "GND")
			(pinfunction "VSS")
			(pintype "passive")
		)
	)
)
